# BASEBOARD_FAB2 (Tioga Pass) — schematic netlist excerpt (pin names and nets, part order shuffled) for the footprints in the layout excerpt that follows; sources: Cadence DE-HDL packaged netlist, KiCad conversion of Wiwynn_Tioga_Pass_MB.brd

J8E4  SCONN64_H87568002_A  CONN  pkg SMT  page 188
  IO1  = SMB_OCP_FRU_STBY_LVC3_SCL
  IO2  = SMB_OCP_FRU_STBY_LVC3_SDA
  IO3  = EXT_MDIO_I2C_SEL
  IO4  = GND
  IO5  = NC
  IO6  = NC
  IO7  = GND
  IO8  = LED_GBE_P1_0
  IO9  = LED_GBE_P1_1
  IO10  = GND
  IO11  = NC
  IO12  = NC
  IO13  = GND
  IO14  = LED_GBE_P2_0
  IO15  = LED_GBE_P2_1
  IO16  = GND
  IO17  = NC
  IO18  = NC
  IO19  = GND
  IO20  = SMB_PCH_MEZZ_LOM0_SCL
  IO21  = SMB_PCH_MEZZ_LOM0_SDA
  IO22  = GND
  IO23  = NC
  IO24  = NC
  IO25  = GND
  IO26  = SMB_PCH_MEZZ_LOM1_SCL
  IO27  = SMB_PCH_MEZZ_LOM1_SDA
  IO28  = GND
  IO29  = SMB_PCH_MEZZ_LOM3_SCL
  IO30  = SMB_PCH_MEZZ_LOM3_SDA
  IO31  = FM_GBE2_LVC3_MOD_ABS
  IO32  = FM_GBE3_LVC3_MOD_ABS
  IO33  = P12V_STBY
  IO34  = P12V_STBY
  IO35  = P12V_STBY
  IO36  = TP_RSVD<0>
  IO37  = FM_GBE0_LVC3_MOD_ABS
  IO38  = FM_GBE1_LVC3_MOD_ABS
  IO39  = GND
  IO40  = KR_P0_OCP_TX_DP
  IO41  = KR_P0_OCP_TX_DN
  IO42  = GND
  IO43  = LED_GBE_P0_0
  IO44  = LED_GBE_P0_1
  IO45  = GND
  IO46  = KR_P1_OCP_TX_DP
  IO47  = KR_P1_OCP_TX_DN
  IO48  = GND
  IO49  = TP_SHARED_KR_MDC_0
  IO50  = TP_SHARED_KR_MDIO_0
  IO51  = GND
  IO52  = KR_P0_OCP_RX_DP
  IO53  = KR_P0_OCP_RX_DN
  IO54  = GND
  IO55  = LED_GBE_P3_0
  IO56  = LED_GBE_P3_1
  IO57  = GND
  IO58  = KR_P1_OCP_RX_DP
  IO59  = KR_P1_OCP_RX_DN
  IO60  = GND
  IO61  = SMB_PCH_MEZZ_LOM2_SCL
  IO62  = SMB_PCH_MEZZ_LOM2_SDA
  IO63  = GND
  IO64  = FM_OCP_MEZZC_PRES_N

(kicad_pcb
	(version 20260206)
	(generator "pcbnew")
	(generator_version "10.0")
	(general
		(thickness 1.6)
		(legacy_teardrops no)
	)
	(paper "A4")
	(title_block
		(title "Wiwynn_Tioga_Pass_MB.brd")
		(comment 1 "Tioga Pass / footprint 349 of 4770 (J8E4), pads 1-49 of 66")
	)
	(layers
		(0 "F.Cu" signal "TOP")
		(4 "In1.Cu" signal "L2GND")
		(6 "In2.Cu" signal "L3")
		(8 "In3.Cu" signal "L4GND")
		(10 "In4.Cu" signal "L5")
		(12 "In5.Cu" signal "L6GND")
		(14 "In6.Cu" signal "L7VCC")
		(16 "In7.Cu" signal "L8VCC")
		(18 "In8.Cu" signal "L9GND")
		(20 "In9.Cu" signal "L10")
		(22 "In10.Cu" signal "L11GND")
		(24 "In11.Cu" signal "L12")
		(26 "In12.Cu" signal "L13GND")
		(2 "B.Cu" signal "BOTTOM")
		(9 "F.Adhes" user "F.Adhesive")
		(11 "B.Adhes" user "B.Adhesive")
		(13 "F.Paste" user "Package Geometry/Pastemask Top")
		(15 "B.Paste" user "Package Geometry/Pastemask Bottom")
		(5 "F.SilkS" user "Ref Des/Silkscreen Top")
		(7 "B.SilkS" user "Ref Des/Silkscreen Bottom")
		(1 "F.Mask" user "Board Geometry/Soldermask Top")
		(3 "B.Mask" user "Board Geometry/Soldermask Bottom")
		(17 "Dwgs.User" user "User.Drawings")
		(19 "Cmts.User" user "User.Comments")
		(21 "Eco1.User" user "User.Eco1")
		(23 "Eco2.User" user "User.Eco2")
		(25 "Edge.Cuts" user "Board Geometry/Outline")
		(27 "Margin" user)
		(31 "F.CrtYd" user "Package Geometry/Place Bound Top")
		(29 "B.CrtYd" user "Package Geometry/Place Bound Bottom")
		(35 "F.Fab" user "Ref Des/Assembly Top")
		(33 "B.Fab" user "Ref Des/Assembly Bottom")
	)
	(footprint ""
		(layer "F.Cu")
		(at 440.550046 -57.596024 90)
		(property "Reference" "J8E4"
			(at 1.795272 -4.825746 90)
			(unlocked yes)
			(layer "F.SilkS")
			(effects
				(font
					(size 0.7874 0.5842)
					(thickness 0.1524)
				)
			)
		)
		(property "Value" ""
			(at 0 0 90)
			(layer "F.Fab")
			(effects
				(font
					(size 1.27 1.27)
				)
			)
		)
		(duplicate_pad_numbers_are_jumpers no)
		(pad "" np_thru_hole circle
			(at 2.203196 -2.500122 90)
			(size 0.254 0.254)
			(drill 1.1938)
			(layers "*.Cu" "*.Mask")
			(clearance 0.7874)
			(thermal_gap 0.7874)
		)
		(pad "" np_thru_hole circle
			(at 2.203196 27.29992 90)
			(size 0.254 0.254)
			(drill 0.8128)
			(layers "*.Cu" "*.Mask")
			(clearance 0.5969)
			(thermal_gap 0.5969)
		)
		(pad "1" smd rect
			(at 0 0 90)
			(size 2.0066 0.508)
			(layers "F.Cu" "F.Mask" "F.Paste")
			(net "SMB_OCP_FRU_STBY_LVC3_SCL")
		)
		(pad "2" smd rect
			(at 0 0.8001 90)
			(size 2.0066 0.508)
			(layers "F.Cu" "F.Mask" "F.Paste")
			(net "SMB_OCP_FRU_STBY_LVC3_SDA")
		)
		(pad "3" smd rect
			(at 0 1.599946 90)
			(size 2.0066 0.508)
			(layers "F.Cu" "F.Mask" "F.Paste")
			(net "EXT_MDIO_I2C_SEL")
		)
		(pad "4" smd rect
			(at 0 2.400046 90)
			(size 2.0066 0.508)
			(layers "F.Cu" "F.Mask" "F.Paste")
			(net "GND")
		)
		(pad "5" smd rect
			(at 0 3.199892 90)
			(size 2.0066 0.508)
			(layers "F.Cu" "F.Mask" "F.Paste")
			(net "Net_446")
		)
		(pad "6" smd rect
			(at 0 3.999992 90)
			(size 2.0066 0.508)
			(layers "F.Cu" "F.Mask" "F.Paste")
			(net "Net_445")
		)
		(pad "7" smd rect
			(at 0 4.800092 90)
			(size 2.0066 0.508)
			(layers "F.Cu" "F.Mask" "F.Paste")
			(net "GND")
		)
		(pad "8" smd rect
			(at 0 5.599938 90)
			(size 2.0066 0.508)
			(layers "F.Cu" "F.Mask" "F.Paste")
			(net "LED_GBE_P1_0")
		)
		(pad "9" smd rect
			(at 0 6.400038 90)
			(size 2.0066 0.508)
			(layers "F.Cu" "F.Mask" "F.Paste")
			(net "LED_GBE_P1_1")
		)
		(pad "10" smd rect
			(at 0 7.199884 90)
			(size 2.0066 0.508)
			(layers "F.Cu" "F.Mask" "F.Paste")
			(net "GND")
		)
		(pad "11" smd rect
			(at 0 7.999984 90)
			(size 2.0066 0.508)
			(layers "F.Cu" "F.Mask" "F.Paste")
			(net "Net_450")
		)
		(pad "12" smd rect
			(at 0 8.800084 90)
			(size 2.0066 0.508)
			(layers "F.Cu" "F.Mask" "F.Paste")
			(net "Net_449")
		)
		(pad "13" smd rect
			(at 0 9.59993 90)
			(size 2.0066 0.508)
			(layers "F.Cu" "F.Mask" "F.Paste")
			(net "GND")
		)
		(pad "14" smd rect
			(at 0 10.40003 90)
			(size 2.0066 0.508)
			(layers "F.Cu" "F.Mask" "F.Paste")
			(net "LED_GBE_P2_0")
		)
		(pad "15" smd rect
			(at 0 11.199876 90)
			(size 2.0066 0.508)
			(layers "F.Cu" "F.Mask" "F.Paste")
			(net "LED_GBE_P2_1")
		)
		(pad "16" smd rect
			(at 0 11.999976 90)
			(size 2.0066 0.508)
			(layers "F.Cu" "F.Mask" "F.Paste")
			(net "GND")
		)
		(pad "17" smd rect
			(at 0 12.800076 90)
			(size 2.0066 0.508)
			(layers "F.Cu" "F.Mask" "F.Paste")
			(net "Net_444")
		)
		(pad "18" smd rect
			(at 0 13.599922 90)
			(size 2.0066 0.508)
			(layers "F.Cu" "F.Mask" "F.Paste")
			(net "Net_443")
		)
		(pad "19" smd rect
			(at 0 14.400022 90)
			(size 2.0066 0.508)
			(layers "F.Cu" "F.Mask" "F.Paste")
			(net "GND")
		)
		(pad "20" smd rect
			(at 0 15.200122 90)
			(size 2.0066 0.508)
			(layers "F.Cu" "F.Mask" "F.Paste")
			(net "SMB_PCH_MEZZ_LOM0_SCL")
		)
		(pad "21" smd rect
			(at 0 15.999968 90)
			(size 2.0066 0.508)
			(layers "F.Cu" "F.Mask" "F.Paste")
			(net "SMB_PCH_MEZZ_LOM0_SDA")
		)
		(pad "22" smd rect
			(at 0 16.800068 90)
			(size 2.0066 0.508)
			(layers "F.Cu" "F.Mask" "F.Paste")
			(net "GND")
		)
		(pad "23" smd rect
			(at 0 17.599914 90)
			(size 2.0066 0.508)
			(layers "F.Cu" "F.Mask" "F.Paste")
			(net "Net_448")
		)
		(pad "24" smd rect
			(at 0 18.400014 90)
			(size 2.0066 0.508)
			(layers "F.Cu" "F.Mask" "F.Paste")
			(net "Net_447")
		)
		(pad "25" smd rect
			(at 0 19.200114 90)
			(size 2.0066 0.508)
			(layers "F.Cu" "F.Mask" "F.Paste")
			(net "GND")
		)
		(pad "26" smd rect
			(at 0 19.99996 90)
			(size 2.0066 0.508)
			(layers "F.Cu" "F.Mask" "F.Paste")
			(net "SMB_PCH_MEZZ_LOM1_SCL")
		)
		(pad "27" smd rect
			(at 0 20.80006 90)
			(size 2.0066 0.508)
			(layers "F.Cu" "F.Mask" "F.Paste")
			(net "SMB_PCH_MEZZ_LOM1_SDA")
		)
		(pad "28" smd rect
			(at 0 21.599906 90)
			(size 2.0066 0.508)
			(layers "F.Cu" "F.Mask" "F.Paste")
			(net "GND")
		)
		(pad "29" smd rect
			(at 0 22.400006 90)
			(size 2.0066 0.508)
			(layers "F.Cu" "F.Mask" "F.Paste")
			(net "SMB_PCH_MEZZ_LOM3_SCL")
		)
		(pad "30" smd rect
			(at 0 23.200106 90)
			(size 2.0066 0.508)
			(layers "F.Cu" "F.Mask" "F.Paste")
			(net "SMB_PCH_MEZZ_LOM3_SDA")
		)
		(pad "31" smd rect
			(at 0 23.999952 90)
			(size 2.0066 0.508)
			(layers "F.Cu" "F.Mask" "F.Paste")
			(net "FM_GBE2_LVC3_MOD_ABS")
		)
		(pad "32" smd rect
			(at 0 24.800052 90)
			(size 2.0066 0.508)
			(layers "F.Cu" "F.Mask" "F.Paste")
			(net "FM_GBE3_LVC3_MOD_ABS")
		)
		(pad "33" smd rect
			(at 4.406646 0 90)
			(size 2.0066 0.508)
			(layers "F.Cu" "F.Mask" "F.Paste")
			(net "P12V_STBY")
		)
		(pad "34" smd rect
			(at 4.406646 0.8001 90)
			(size 2.0066 0.508)
			(layers "F.Cu" "F.Mask" "F.Paste")
			(net "P12V_STBY")
		)
		(pad "35" smd rect
			(at 4.406646 1.599946 90)
			(size 2.0066 0.508)
			(layers "F.Cu" "F.Mask" "F.Paste")
			(net "P12V_STBY")
		)
		(pad "36" smd rect
			(at 4.406646 2.400046 90)
			(size 2.0066 0.508)
			(layers "F.Cu" "F.Mask" "F.Paste")
			(net "TP_RSVD<0>")
		)
		(pad "37" smd rect
			(at 4.406646 3.199892 90)
			(size 2.0066 0.508)
			(layers "F.Cu" "F.Mask" "F.Paste")
			(net "FM_GBE0_LVC3_MOD_ABS")
		)
		(pad "38" smd rect
			(at 4.406646 3.999992 90)
			(size 2.0066 0.508)
			(layers "F.Cu" "F.Mask" "F.Paste")
			(net "FM_GBE1_LVC3_MOD_ABS")
		)
		(pad "39" smd rect
			(at 4.406646 4.800092 90)
			(size 2.0066 0.508)
			(layers "F.Cu" "F.Mask" "F.Paste")
			(net "GND")
		)
		(pad "40" smd rect
			(at 4.406646 5.599938 90)
			(size 2.0066 0.508)
			(layers "F.Cu" "F.Mask" "F.Paste")
			(net "KR_P0_OCP_TX_DP")
		)
		(pad "41" smd rect
			(at 4.406646 6.400038 90)
			(size 2.0066 0.508)
			(layers "F.Cu" "F.Mask" "F.Paste")
			(net "KR_P0_OCP_TX_DN")
		)
		(pad "42" smd rect
			(at 4.406646 7.199884 90)
			(size 2.0066 0.508)
			(layers "F.Cu" "F.Mask" "F.Paste")
			(net "GND")
		)
		(pad "43" smd rect
			(at 4.406646 7.999984 90)
			(size 2.0066 0.508)
			(layers "F.Cu" "F.Mask" "F.Paste")
			(net "LED_GBE_P0_0")
		)
		(pad "44" smd rect
			(at 4.406646 8.800084 90)
			(size 2.0066 0.508)
			(layers "F.Cu" "F.Mask" "F.Paste")
			(net "LED_GBE_P0_1")
		)
		(pad "45" smd rect
			(at 4.406646 9.59993 90)
			(size 2.0066 0.508)
			(layers "F.Cu" "F.Mask" "F.Paste")
			(net "GND")
		)
		(pad "46" smd rect
			(at 4.406646 10.40003 90)
			(size 2.0066 0.508)
			(layers "F.Cu" "F.Mask" "F.Paste")
			(net "KR_P1_OCP_TX_DP")
		)
		(pad "47" smd rect
			(at 4.406646 11.199876 90)
			(size 2.0066 0.508)
			(layers "F.Cu" "F.Mask" "F.Paste")
			(net "KR_P1_OCP_TX_DN")
		)
	)
)
